(kicad_pcb
	(version 20260206)
	(generator "pcbnew")
	(generator_version "10.0")
	(general
		(thickness 1.6)
		(legacy_teardrops no)
	)
	(paper "A4")
	(title_block
		(title "12092022_DA0F0TMDCD0_F0T_Management_Board_D_brd_V3_OCP.brd")
		(comment 1 "Grand Teton / footprint 124 of 1440 (U5), pads 111-221 of 624")
	)
	(layers
		(0 "F.Cu" signal "TOP")
		(4 "In1.Cu" signal "GND")
		(6 "In2.Cu" signal "IN1")
		(8 "In3.Cu" signal "GND1")
		(10 "In4.Cu" signal "IN2")
		(12 "In5.Cu" signal "VCC")
		(14 "In6.Cu" signal "VCC1")
		(16 "In7.Cu" signal "IN3")
		(18 "In8.Cu" signal "GND2")
		(20 "In9.Cu" signal "IN4")
		(22 "In10.Cu" signal "GND3")
		(2 "B.Cu" signal "BOTTOM")
		(9 "F.Adhes" user "F.Adhesive")
		(11 "B.Adhes" user "B.Adhesive")
		(13 "F.Paste" user "Package Geometry/Pastemask Top")
		(15 "B.Paste" user "Package Geometry/Pastemask Bottom")
		(5 "F.SilkS" user "Ref Des/Silkscreen Top")
		(7 "B.SilkS" user "Ref Des/Silkscreen Bottom")
		(1 "F.Mask" user "Board Geometry/Soldermask Top")
		(3 "B.Mask" user "Board Geometry/Soldermask Bottom")
		(17 "Dwgs.User" user "User.Drawings")
		(19 "Cmts.User" user "User.Comments")
		(21 "Eco1.User" user "User.Eco1")
		(23 "Eco2.User" user "User.Eco2")
		(25 "Edge.Cuts" user "Board Geometry/Outline")
		(27 "Margin" user)
		(31 "F.CrtYd" user "Package Geometry/Place Bound Top")
		(29 "B.CrtYd" user "Package Geometry/Place Bound Bottom")
		(35 "F.Fab" user "Ref Des/Assembly Top")
		(33 "B.Fab" user "Ref Des/Assembly Bottom")
	)
	(footprint ""
		(layer "F.Cu")
		(at 54.894988 -49.37125 180)
		(property "Reference" "U5"
			(at -11.094212 -12.07262 0)
			(unlocked yes)
			(layer "F.SilkS")
			(effects
				(font
					(size 0.7874 0.5842)
					(thickness 0.1524)
				)
				(justify left)
			)
		)
		(property "Value" ""
			(at 0 0 180)
			(layer "F.Fab")
			(effects
				(font
					(size 1.27 1.27)
				)
			)
		)
		(duplicate_pad_numbers_are_jumpers no)
		(pad "AD7" smd circle
			(at -5.199888 8.400034 180)
			(size 0.4064 0.4064)
			(layers "F.Cu" "F.Mask" "F.Paste")
			(net "IRQ_ESPI_LPC_SERIRQ_ALERT0_N")
		)
		(pad "AD8" smd circle
			(at -4.400042 8.400034 180)
			(size 0.4064 0.4064)
			(layers "F.Cu" "F.Mask" "F.Paste")
			(net "RST_ESPI_LPC_BMC_N")
		)
		(pad "AD9" smd circle
			(at -3.599942 8.400034 180)
			(size 0.4064 0.4064)
			(layers "F.Cu" "F.Mask" "F.Paste")
			(net "SPI_BMC_BIOS_ROM_MISO")
		)
		(pad "AD10" smd circle
			(at -2.800096 8.400034 180)
			(size 0.4064 0.4064)
			(layers "F.Cu" "F.Mask" "F.Paste")
			(net "PU_SPI1ABR")
		)
		(pad "AD11" smd circle
			(at -1.999996 8.400034 180)
			(size 0.4064 0.4064)
			(layers "F.Cu" "F.Mask" "F.Paste")
			(net "FM_DEBUG_PORT_PRSNT_R1_N")
		)
		(pad "AD12" smd circle
			(at -1.199896 8.400034 180)
			(size 0.4064 0.4064)
			(layers "F.Cu" "F.Mask" "F.Paste")
			(net "RST_WDTRST_PLD_R1_N")
		)
		(pad "AD13" smd circle
			(at -0.40005 8.400034 180)
			(size 0.4064 0.4064)
			(layers "F.Cu" "F.Mask" "F.Paste")
			(net "TP_BMC_SPICS0_N")
		)
		(pad "AD14" smd circle
			(at 0.40005 8.400034 180)
			(size 0.4064 0.4064)
			(layers "F.Cu" "F.Mask" "F.Paste")
			(net "BMC_ID_BEEP_SEL_R1")
		)
		(pad "AD15" smd circle
			(at 1.199896 8.400034 180)
			(size 0.4064 0.4064)
			(layers "F.Cu" "F.Mask" "F.Paste")
			(net "FM_BMC_SUSACK_R1_N")
		)
		(pad "AD16" smd circle
			(at 1.999996 8.400034 180)
			(size 0.4064 0.4064)
			(layers "F.Cu" "F.Mask" "F.Paste")
			(net "FM_PCHHOT_R_N")
		)
		(pad "AD17" smd circle
			(at 2.800096 8.400034 180)
			(size 0.4064 0.4064)
			(layers "F.Cu" "F.Mask" "F.Paste")
			(net "A_BMC_ADCVREFP1")
		)
		(pad "AD18" smd circle
			(at 3.599942 8.400034 180)
			(size 0.4064 0.4064)
			(layers "F.Cu" "F.Mask" "F.Paste")
			(net "A_BMC_ADCVREFN1")
		)
		(pad "AD19" smd circle
			(at 4.400042 8.400034 180)
			(size 0.4064 0.4064)
			(layers "F.Cu" "F.Mask" "F.Paste")
			(net "P2V5_SENSOR")
		)
		(pad "AD20" smd circle
			(at 5.199888 8.400034 180)
			(size 0.4064 0.4064)
			(layers "F.Cu" "F.Mask" "F.Paste")
			(net "P12V_SENSOR")
		)
		(pad "AD21" smd circle
			(at 5.999988 8.400034 180)
			(size 0.4064 0.4064)
			(layers "F.Cu" "F.Mask" "F.Paste")
			(net "V_DACB_R")
		)
		(pad "AD22" smd circle
			(at 6.800088 8.400034 180)
			(size 0.4064 0.4064)
			(layers "F.Cu" "F.Mask" "F.Paste")
			(net "Net_33")
		)
		(pad "AD23" smd circle
			(at 7.599934 8.400034 180)
			(size 0.4064 0.4064)
			(layers "F.Cu" "F.Mask" "F.Paste")
			(net "FM_PCIE_M2_SSD0_PRSNT_N")
		)
		(pad "AD24" smd circle
			(at 8.400034 8.400034 180)
			(size 0.4064 0.4064)
			(layers "F.Cu" "F.Mask" "F.Paste")
			(net "FM_JTAG_BMC_MUX_SEL_R1")
		)
		(pad "AD25" smd circle
			(at 9.19988 8.400034 180)
			(size 0.4064 0.4064)
			(layers "F.Cu" "F.Mask" "F.Paste")
			(net "FM_ADR_TRIGGER_N")
		)
		(pad "AD26" smd circle
			(at 9.99998 8.400034 180)
			(size 0.4064 0.4064)
			(layers "F.Cu" "F.Mask" "F.Paste")
			(net "FM_PMBUS_ALERT_EN")
		)
		(pad "AE1" smd circle
			(at -9.99998 9.19988 180)
			(size 0.4064 0.4064)
			(layers "F.Cu" "F.Mask" "F.Paste")
			(net "CLK_100M_GPU_DP")
		)
		(pad "AE2" smd circle
			(at -9.19988 9.19988 180)
			(size 0.4064 0.4064)
			(layers "F.Cu" "F.Mask" "F.Paste")
			(net "CLK_100M_GPU_DN")
		)
		(pad "AE3" smd circle
			(at -8.400034 9.19988 180)
			(size 0.4064 0.4064)
			(layers "F.Cu" "F.Mask" "F.Paste")
			(net "GND")
		)
		(pad "AE4" smd circle
			(at -7.599934 9.19988 180)
			(size 0.4064 0.4064)
			(layers "F.Cu" "F.Mask" "F.Paste")
			(net "P2E_PCH_TX_DP")
		)
		(pad "AE5" smd circle
			(at -6.800088 9.19988 180)
			(size 0.4064 0.4064)
			(layers "F.Cu" "F.Mask" "F.Paste")
			(net "P2E_PCH_TX_DN")
		)
		(pad "AE6" smd circle
			(at -5.999988 9.19988 180)
			(size 0.4064 0.4064)
			(layers "F.Cu" "F.Mask" "F.Paste")
			(net "GND")
		)
		(pad "AE7" smd circle
			(at -5.199888 9.19988 180)
			(size 0.4064 0.4064)
			(layers "F.Cu" "F.Mask" "F.Paste")
			(net "ESPI_HOST_LPC_BMC_CLK_R")
		)
		(pad "AE8" smd circle
			(at -4.400042 9.19988 180)
			(size 0.4064 0.4064)
			(layers "F.Cu" "F.Mask" "F.Paste")
			(net "SPI_BMC_BIOS_CS0_R1_N")
		)
		(pad "AE9" smd circle
			(at -3.599942 9.19988 180)
			(size 0.4064 0.4064)
			(layers "F.Cu" "F.Mask" "F.Paste")
			(net "GND")
		)
		(pad "AE10" smd circle
			(at -2.800096 9.19988 180)
			(size 0.4064 0.4064)
			(layers "F.Cu" "F.Mask" "F.Paste")
			(net "PU_SPI1WP_N")
		)
		(pad "AE11" smd circle
			(at -1.999996 9.19988 180)
			(size 0.4064 0.4064)
			(layers "F.Cu" "F.Mask" "F.Paste")
			(net "FM_FLASH_LATCH_N_R1")
		)
		(pad "AE12" smd circle
			(at -1.199896 9.19988 180)
			(size 0.4064 0.4064)
			(layers "F.Cu" "F.Mask" "F.Paste")
			(net "SPI_BMC_IO2_R")
		)
		(pad "AE13" smd circle
			(at -0.40005 9.19988 180)
			(size 0.4064 0.4064)
			(layers "F.Cu" "F.Mask" "F.Paste")
			(net "GND")
		)
		(pad "AE14" smd circle
			(at 0.40005 9.19988 180)
			(size 0.4064 0.4064)
			(layers "F.Cu" "F.Mask" "F.Paste")
			(net "FM_BMC_READY_R_PLD_N")
		)
		(pad "AE15" smd circle
			(at 1.199896 9.19988 180)
			(size 0.4064 0.4064)
			(layers "F.Cu" "F.Mask" "F.Paste")
			(net "BATTERY_DETECT")
		)
		(pad "AE16" smd circle
			(at 1.999996 9.19988 180)
			(size 0.4064 0.4064)
			(layers "F.Cu" "F.Mask" "F.Paste")
			(net "SMB_BMC_ALERT12_N")
		)
		(pad "AE17" smd circle
			(at 2.800096 9.19988 180)
			(size 0.4064 0.4064)
			(layers "F.Cu" "F.Mask" "F.Paste")
			(net "GND")
		)
		(pad "AE18" smd circle
			(at 3.599942 9.19988 180)
			(size 0.4064 0.4064)
			(layers "F.Cu" "F.Mask" "F.Paste")
			(net "P3V_BAT_SENSOR")
		)
		(pad "AE19" smd circle
			(at 4.400042 9.19988 180)
			(size 0.4064 0.4064)
			(layers "F.Cu" "F.Mask" "F.Paste")
			(net "P3V3_SENSOR")
		)
		(pad "AE20" smd circle
			(at 5.199888 9.19988 180)
			(size 0.4064 0.4064)
			(layers "F.Cu" "F.Mask" "F.Paste")
			(net "GND")
		)
		(pad "AE21" smd circle
			(at 5.999988 9.19988 180)
			(size 0.4064 0.4064)
			(layers "F.Cu" "F.Mask" "F.Paste")
			(net "V_DACG_R")
		)
		(pad "AE22" smd circle
			(at 6.800088 9.19988 180)
			(size 0.4064 0.4064)
			(layers "F.Cu" "F.Mask" "F.Paste")
			(net "I3C2_SDA_R")
		)
		(pad "AE23" smd circle
			(at 7.599934 9.19988 180)
			(size 0.4064 0.4064)
			(layers "F.Cu" "F.Mask" "F.Paste")
			(net "GND")
		)
		(pad "AE24" smd circle
			(at 8.400034 9.19988 180)
			(size 0.4064 0.4064)
			(layers "F.Cu" "F.Mask" "F.Paste")
			(net "I3C1_SDA_R")
		)
		(pad "AE25" smd circle
			(at 9.19988 9.19988 180)
			(size 0.4064 0.4064)
			(layers "F.Cu" "F.Mask" "F.Paste")
			(net "I3C4_SCL_R")
		)
		(pad "AE26" smd circle
			(at 9.99998 9.19988 180)
			(size 0.4064 0.4064)
			(layers "F.Cu" "F.Mask" "F.Paste")
			(net "I3C3_SDA_R")
		)
		(pad "AF1" smd circle
			(at -9.99998 9.99998 180)
			(size 0.4064 0.4064)
			(layers "F.Cu" "F.Mask" "F.Paste")
			(net "GND")
		)
		(pad "AF2" smd circle
			(at -9.19988 9.99998 180)
			(size 0.4064 0.4064)
			(layers "F.Cu" "F.Mask" "F.Paste")
			(net "P2E_GPU_TX_DN")
		)
		(pad "AF3" smd circle
			(at -8.400034 9.99998 180)
			(size 0.4064 0.4064)
			(layers "F.Cu" "F.Mask" "F.Paste")
			(net "P2E_GPU_TX_DP")
		)
		(pad "AF4" smd circle
			(at -7.599934 9.99998 180)
			(size 0.4064 0.4064)
			(layers "F.Cu" "F.Mask" "F.Paste")
			(net "GND")
		)
		(pad "AF5" smd circle
			(at -6.800088 9.99998 180)
			(size 0.4064 0.4064)
			(layers "F.Cu" "F.Mask" "F.Paste")
			(net "P2E_PCH_RX_DP")
		)
		(pad "AF6" smd circle
			(at -5.999988 9.99998 180)
			(size 0.4064 0.4064)
			(layers "F.Cu" "F.Mask" "F.Paste")
			(net "P2E_PCH_RX_DN")
		)
		(pad "AF7" smd circle
			(at -5.199888 9.99998 180)
			(size 0.4064 0.4064)
			(layers "F.Cu" "F.Mask" "F.Paste")
			(net "ESPI_HOST_LPC_BMC_LFRAME_N_R")
		)
		(pad "AF8" smd circle
			(at -4.400042 9.99998 180)
			(size 0.4064 0.4064)
			(layers "F.Cu" "F.Mask" "F.Paste")
			(net "SPI_BMC_BIOS_ROM_CLK")
		)
		(pad "AF9" smd circle
			(at -3.599942 9.99998 180)
			(size 0.4064 0.4064)
			(layers "F.Cu" "F.Mask" "F.Paste")
			(net "SPI_BMC_BIOS_ROM_IO2")
		)
		(pad "AF10" smd circle
			(at -2.800096 9.99998 180)
			(size 0.4064 0.4064)
			(layers "F.Cu" "F.Mask" "F.Paste")
			(net "CLK_GEN2_BMC_RC_OE_N")
		)
		(pad "AF11" smd circle
			(at -1.999996 9.99998 180)
			(size 0.4064 0.4064)
			(layers "F.Cu" "F.Mask" "F.Paste")
			(net "RST_BMC_SELF_HW_R1")
		)
		(pad "AF12" smd circle
			(at -1.199896 9.99998 180)
			(size 0.4064 0.4064)
			(layers "F.Cu" "F.Mask" "F.Paste")
			(net "SPI_BMC_IO3_R")
		)
		(pad "AF13" smd circle
			(at -0.40005 9.99998 180)
			(size 0.4064 0.4064)
			(layers "F.Cu" "F.Mask" "F.Paste")
			(net "SPI_BMC_CLK_R")
		)
		(pad "AF14" smd circle
			(at 0.40005 9.99998 180)
			(size 0.4064 0.4064)
			(layers "F.Cu" "F.Mask" "F.Paste")
			(net "RST_RSMRST_R_N")
		)
		(pad "AF15" smd circle
			(at 1.199896 9.99998 180)
			(size 0.4064 0.4064)
			(layers "F.Cu" "F.Mask" "F.Paste")
			(net "IRQ_TPM_SPI_N")
		)
		(pad "AF16" smd circle
			(at 1.999996 9.99998 180)
			(size 0.4064 0.4064)
			(layers "F.Cu" "F.Mask" "F.Paste")
			(net "PECI_BMC_R")
		)
		(pad "AF17" smd circle
			(at 2.800096 9.99998 180)
			(size 0.4064 0.4064)
			(layers "F.Cu" "F.Mask" "F.Paste")
			(net "ADCVREFEXT1")
		)
		(pad "AF18" smd circle
			(at 3.599942 9.99998 180)
			(size 0.4064 0.4064)
			(layers "F.Cu" "F.Mask" "F.Paste")
			(net "A_BMC_ADCREXT1")
		)
		(pad "AF19" smd circle
			(at 4.400042 9.99998 180)
			(size 0.4064 0.4064)
			(layers "F.Cu" "F.Mask" "F.Paste")
			(net "ADCVREFEXT0")
		)
		(pad "AF20" smd circle
			(at 5.199888 9.99998 180)
			(size 0.4064 0.4064)
			(layers "F.Cu" "F.Mask" "F.Paste")
			(net "A_BMC_ADCREXT0")
		)
		(pad "AF21" smd circle
			(at 5.999988 9.99998 180)
			(size 0.4064 0.4064)
			(layers "F.Cu" "F.Mask" "F.Paste")
			(net "V_DACR_R")
		)
		(pad "AF22" smd circle
			(at 6.800088 9.99998 180)
			(size 0.4064 0.4064)
			(layers "F.Cu" "F.Mask" "F.Paste")
			(net "I3C2_SCL_R")
		)
		(pad "AF23" smd circle
			(at 7.599934 9.99998 180)
			(size 0.4064 0.4064)
			(layers "F.Cu" "F.Mask" "F.Paste")
			(net "I3C1_SCL_R")
		)
		(pad "AF24" smd circle
			(at 8.400034 9.99998 180)
			(size 0.4064 0.4064)
			(layers "F.Cu" "F.Mask" "F.Paste")
			(net "I3C4_SDA_R")
		)
		(pad "AF25" smd circle
			(at 9.19988 9.99998 180)
			(size 0.4064 0.4064)
			(layers "F.Cu" "F.Mask" "F.Paste")
			(net "I3C3_SCL_R")
		)
		(pad "AF26" smd circle
			(at 9.99998 9.99998 180)
			(size 0.4064 0.4064)
			(layers "F.Cu" "F.Mask" "F.Paste")
			(net "GND")
		)
		(pad "B1" smd circle
			(at -9.99998 -9.19988 180)
			(size 0.4064 0.4064)
			(layers "F.Cu" "F.Mask" "F.Paste")
			(net "Net_55")
		)
		(pad "B2" smd circle
			(at -9.19988 -9.19988 180)
			(size 0.4064 0.4064)
			(layers "F.Cu" "F.Mask" "F.Paste")
			(net "Net_56")
		)
		(pad "B3" smd circle
			(at -8.400034 -9.19988 180)
			(size 0.4064 0.4064)
			(layers "F.Cu" "F.Mask" "F.Paste")
			(net "Net_36")
		)
		(pad "B4" smd circle
			(at -7.599934 -9.19988 180)
			(size 0.4064 0.4064)
			(layers "F.Cu" "F.Mask" "F.Paste")
			(net "USB_HOST_BMC_A_R_DN")
		)
		(pad "B5" smd circle
			(at -6.800088 -9.19988 180)
			(size 0.4064 0.4064)
			(layers "F.Cu" "F.Mask" "F.Paste")
			(net "GND")
		)
		(pad "B6" smd circle
			(at -5.999988 -9.19988 180)
			(size 0.4064 0.4064)
			(layers "F.Cu" "F.Mask" "F.Paste")
			(net "USB_HOST_BMC_B_R_DN")
		)
		(pad "B7" smd circle
			(at -5.199888 -9.19988 180)
			(size 0.4064 0.4064)
			(layers "F.Cu" "F.Mask" "F.Paste")
			(net "RST_SPI_FLASH_N")
		)
		(pad "B8" smd circle
			(at -4.400042 -9.19988 180)
			(size 0.4064 0.4064)
			(layers "F.Cu" "F.Mask" "F.Paste")
			(net "V_BMC_DDC_SCL")
		)
		(pad "B9" smd circle
			(at -3.599942 -9.19988 180)
			(size 0.4064 0.4064)
			(layers "F.Cu" "F.Mask" "F.Paste")
			(net "JTAG_SCM_TCK")
		)
		(pad "B10" smd circle
			(at -2.800096 -9.19988 180)
			(size 0.4064 0.4064)
			(layers "F.Cu" "F.Mask" "F.Paste")
			(net "RST_EXTRST_N")
		)
		(pad "B11" smd circle
			(at -1.999996 -9.19988 180)
			(size 0.4064 0.4064)
			(layers "F.Cu" "F.Mask" "F.Paste")
			(net "GND")
		)
		(pad "B12" smd circle
			(at -1.199896 -9.19988 180)
			(size 0.4064 0.4064)
			(layers "F.Cu" "F.Mask" "F.Paste")
			(net "PWRGD_SYS_PWROK_BMC")
		)
		(pad "B13" smd circle
			(at -0.40005 -9.19988 180)
			(size 0.4064 0.4064)
			(layers "F.Cu" "F.Mask" "F.Paste")
			(net "FM_VIRTUAL_RESEAT_BMC")
		)
		(pad "B14" smd circle
			(at 0.40005 -9.19988 180)
			(size 0.4064 0.4064)
			(layers "F.Cu" "F.Mask" "F.Paste")
			(net "V_VGAHS_R")
		)
		(pad "B15" smd circle
			(at 1.199896 -9.19988 180)
			(size 0.4064 0.4064)
			(layers "F.Cu" "F.Mask" "F.Paste")
			(net "GND")
		)
		(pad "B16" smd circle
			(at 1.999996 -9.19988 180)
			(size 0.4064 0.4064)
			(layers "F.Cu" "F.Mask" "F.Paste")
			(net "FM_THROTTLE_N")
		)
		(pad "B17" smd circle
			(at 2.800096 -9.19988 180)
			(size 0.4064 0.4064)
			(layers "F.Cu" "F.Mask" "F.Paste")
			(net "SMB_BMC_MM15_R_SDA")
		)
		(pad "B18" smd circle
			(at 3.599942 -9.19988 180)
			(size 0.4064 0.4064)
			(layers "F.Cu" "F.Mask" "F.Paste")
			(net "SGPIO_BMC_M1_LD")
		)
		(pad "B19" smd circle
			(at 4.400042 -9.19988 180)
			(size 0.4064 0.4064)
			(layers "F.Cu" "F.Mask" "F.Paste")
			(net "GND")
		)
		(pad "B20" smd circle
			(at 5.199888 -9.19988 180)
			(size 0.4064 0.4064)
			(layers "F.Cu" "F.Mask" "F.Paste")
			(net "SMB_BMC_MM1_R_SCL")
		)
		(pad "B21" smd circle
			(at 5.999988 -9.19988 180)
			(size 0.4064 0.4064)
			(layers "F.Cu" "F.Mask" "F.Paste")
			(net "FM_BMC_DBP_PRESENT_R_N")
		)
		(pad "B22" smd circle
			(at 6.800088 -9.19988 180)
			(size 0.4064 0.4064)
			(layers "F.Cu" "F.Mask" "F.Paste")
			(net "UART_6_BMC_R_RXD")
		)
		(pad "B23" smd circle
			(at 7.599934 -9.19988 180)
			(size 0.4064 0.4064)
			(layers "F.Cu" "F.Mask" "F.Paste")
			(net "GND")
		)
		(pad "B24" smd circle
			(at 8.400034 -9.19988 180)
			(size 0.4064 0.4064)
			(layers "F.Cu" "F.Mask" "F.Paste")
			(net "RMII_RXER")
		)
		(pad "B25" smd circle
			(at 9.19988 -9.19988 180)
			(size 0.4064 0.4064)
			(layers "F.Cu" "F.Mask" "F.Paste")
			(net "RMII_CSRDV")
		)
		(pad "B26" smd circle
			(at 9.99998 -9.19988 180)
			(size 0.4064 0.4064)
			(layers "F.Cu" "F.Mask" "F.Paste")
			(net "RMII_RXD1")
		)
		(pad "C1" smd circle
			(at -9.99998 -8.400034 180)
			(size 0.4064 0.4064)
			(layers "F.Cu" "F.Mask" "F.Paste")
			(net "Net_41")
		)
		(pad "C2" smd circle
			(at -9.19988 -8.400034 180)
			(size 0.4064 0.4064)
			(layers "F.Cu" "F.Mask" "F.Paste")
			(net "Net_163")
		)
		(pad "C3" smd circle
			(at -8.400034 -8.400034 180)
			(size 0.4064 0.4064)
			(layers "F.Cu" "F.Mask" "F.Paste")
			(net "GND")
		)
		(pad "C4" smd circle
			(at -7.599934 -8.400034 180)
			(size 0.4064 0.4064)
			(layers "F.Cu" "F.Mask" "F.Paste")
			(net "Net_54")
		)
		(pad "C5" smd circle
			(at -6.800088 -8.400034 180)
			(size 0.4064 0.4064)
			(layers "F.Cu" "F.Mask" "F.Paste")
			(net "Net_167")
		)
		(pad "C6" smd circle
			(at -5.999988 -8.400034 180)
			(size 0.4064 0.4064)
			(layers "F.Cu" "F.Mask" "F.Paste")
			(net "AC_PWR_BMC_BTN_R_N")
		)
		(pad "C7" smd circle
			(at -5.199888 -8.400034 180)
			(size 0.4064 0.4064)
			(layers "F.Cu" "F.Mask" "F.Paste")
			(net "DP_BMC_HPD_3V3_BUF")
		)
		(pad "C8" smd circle
			(at -4.400042 -8.400034 180)
			(size 0.4064 0.4064)
			(layers "F.Cu" "F.Mask" "F.Paste")
			(net "UART_BMC_5_TXD")
		)
		(pad "C9" smd circle
			(at -3.599942 -8.400034 180)
			(size 0.4064 0.4064)
			(layers "F.Cu" "F.Mask" "F.Paste")
			(net "JTAG_SCM_TDO")
		)
		(pad "C10" smd circle
			(at -2.800096 -8.400034 180)
			(size 0.4064 0.4064)
			(layers "F.Cu" "F.Mask" "F.Paste")
			(net "PD_SP_ENTEST")
		)
		(pad "C11" smd circle
			(at -1.999996 -8.400034 180)
			(size 0.4064 0.4064)
			(layers "F.Cu" "F.Mask" "F.Paste")
			(net "SMB_BMC_MM5_R_SDA")
		)
		(pad "C12" smd circle
			(at -1.199896 -8.400034 180)
			(size 0.4064 0.4064)
			(layers "F.Cu" "F.Mask" "F.Paste")
			(net "FM_DBP_BMC_PRDY_R_N")
		)
		(pad "C13" smd circle
			(at -0.40005 -8.400034 180)
			(size 0.4064 0.4064)
			(layers "F.Cu" "F.Mask" "F.Paste")
			(net "UART_BMC_1_TXD")
		)
	)
)
